(kicad_pcb
	(version 20260206)
	(generator "pcbnew")
	(generator_version "10.0")
	(general
		(thickness 1.6)
		(legacy_teardrops no)
	)
	(paper "A4")
	(title_block
		(title "12092022_DA0F0TFB6D0_F0T_FAN_BOARD_MP5048_D_brd_v02_OCP.brd")
		(comment 1 "Grand Teton / footprints 363-369 of 924")
	)
	(layers
		(0 "F.Cu" signal "TOP")
		(4 "In1.Cu" signal "GND")
		(6 "In2.Cu" signal "IN1")
		(8 "In3.Cu" signal "IN2")
		(10 "In4.Cu" signal "GND1")
		(2 "B.Cu" signal "BOTTOM")
		(9 "F.Adhes" user "F.Adhesive")
		(11 "B.Adhes" user "B.Adhesive")
		(13 "F.Paste" user "Package Geometry/Pastemask Top")
		(15 "B.Paste" user "Package Geometry/Pastemask Bottom")
		(5 "F.SilkS" user "Ref Des/Silkscreen Top")
		(7 "B.SilkS" user "Ref Des/Silkscreen Bottom")
		(1 "F.Mask" user "Board Geometry/Soldermask Top")
		(3 "B.Mask" user "Board Geometry/Soldermask Bottom")
		(17 "Dwgs.User" user "User.Drawings")
		(19 "Cmts.User" user "User.Comments")
		(21 "Eco1.User" user "User.Eco1")
		(23 "Eco2.User" user "User.Eco2")
		(25 "Edge.Cuts" user "Board Geometry/Outline")
		(27 "Margin" user)
		(31 "F.CrtYd" user "Package Geometry/Place Bound Top")
		(29 "B.CrtYd" user "Package Geometry/Place Bound Bottom")
		(35 "F.Fab" user "Ref Des/Assembly Top")
		(33 "B.Fab" user "Ref Des/Assembly Bottom")
	)
	(footprint ""
		(layer "F.Cu")
		(at 14.351 -109.023912)
		(property "Reference" "R5205"
			(at 0 0 0)
			(layer "F.SilkS")
			(hide yes)
			(effects
				(font
					(size 1.27 1.27)
				)
			)
		)
		(property "Value" ""
			(at 0 0 0)
			(layer "F.Fab")
			(effects
				(font
					(size 1.27 1.27)
				)
			)
		)
		(duplicate_pad_numbers_are_jumpers no)
		(fp_line
			(start -0.7874 -0.4064)
			(end 0.7874 -0.4064)
			(stroke
				(width 0.1524)
				(type default)
			)
			(layer "F.SilkS")
		)
		(fp_line
			(start -0.7874 0.4064)
			(end -0.7874 -0.4064)
			(stroke
				(width 0.1524)
				(type default)
			)
			(layer "F.SilkS")
		)
		(fp_line
			(start 0.7874 -0.4064)
			(end 0.7874 0.4064)
			(stroke
				(width 0.1524)
				(type default)
			)
			(layer "F.SilkS")
		)
		(fp_line
			(start 0.7874 0.4064)
			(end -0.7874 0.4064)
			(stroke
				(width 0.1524)
				(type default)
			)
			(layer "F.SilkS")
		)
		(fp_line
			(start -0.67945 -0.305054)
			(end -0.12065 -0.305054)
			(stroke
				(width 0.1)
				(type default)
			)
			(layer "F.Fab")
		)
		(fp_line
			(start -0.67945 0.3048)
			(end -0.67945 -0.305054)
			(stroke
				(width 0.1)
				(type default)
			)
			(layer "F.Fab")
		)
		(fp_line
			(start -0.12065 -0.305054)
			(end -0.12065 -0.2794)
			(stroke
				(width 0.1)
				(type default)
			)
			(layer "F.Fab")
		)
		(fp_line
			(start -0.12065 -0.2794)
			(end 0.12065 -0.2794)
			(stroke
				(width 0.1)
				(type default)
			)
			(layer "F.Fab")
		)
		(fp_line
			(start -0.12065 0.2794)
			(end -0.12065 0.3048)
			(stroke
				(width 0.1)
				(type default)
			)
			(layer "F.Fab")
		)
		(fp_line
			(start -0.12065 0.3048)
			(end -0.67945 0.3048)
			(stroke
				(width 0.1)
				(type default)
			)
			(layer "F.Fab")
		)
		(fp_line
			(start 0.120396 0.2794)
			(end -0.12065 0.2794)
			(stroke
				(width 0.1)
				(type default)
			)
			(layer "F.Fab")
		)
		(fp_line
			(start 0.120396 0.3048)
			(end 0.120396 0.2794)
			(stroke
				(width 0.1)
				(type default)
			)
			(layer "F.Fab")
		)
		(fp_line
			(start 0.12065 -0.3048)
			(end 0.67945 -0.3048)
			(stroke
				(width 0.1)
				(type default)
			)
			(layer "F.Fab")
		)
		(fp_line
			(start 0.12065 -0.2794)
			(end 0.12065 -0.3048)
			(stroke
				(width 0.1)
				(type default)
			)
			(layer "F.Fab")
		)
		(fp_line
			(start 0.67945 -0.3048)
			(end 0.67945 0.3048)
			(stroke
				(width 0.1)
				(type default)
			)
			(layer "F.Fab")
		)
		(fp_line
			(start 0.67945 0.3048)
			(end 0.120396 0.3048)
			(stroke
				(width 0.1)
				(type default)
			)
			(layer "F.Fab")
		)
		(pad "1" smd circle
			(at -0.40005 0)
			(size 0 0)
			(layers "F.Cu" "F.Mask" "F.Paste")
			(net "SMB_FAN5_SDA_R")
		)
		(pad "2" smd circle
			(at 0.40005 0)
			(size 0 0)
			(layers "F.Cu" "F.Mask" "F.Paste")
			(net "SMB_FAN5_SDA")
		)
	)
	(footprint ""
		(layer "F.Cu")
		(at 25.273 -197.104)
		(property "Reference" "U327"
			(at -1.397 1.93167 0)
			(unlocked yes)
			(layer "F.SilkS")
			(effects
				(font
					(size 0.7874 0.5842)
					(thickness 0.1524)
				)
				(justify left)
			)
		)
		(property "Value" ""
			(at 0 0 0)
			(layer "F.Fab")
			(effects
				(font
					(size 1.27 1.27)
				)
			)
		)
		(duplicate_pad_numbers_are_jumpers no)
		(fp_line
			(start -1.538478 -1.150874)
			(end -1.538478 1.150874)
			(stroke
				(width 0.1524)
				(type default)
			)
			(layer "F.SilkS")
		)
		(fp_line
			(start -1.538478 1.150874)
			(end 1.538478 1.150874)
			(stroke
				(width 0.1524)
				(type default)
			)
			(layer "F.SilkS")
		)
		(fp_line
			(start 1.538478 -1.150874)
			(end -1.538478 -1.150874)
			(stroke
				(width 0.1524)
				(type default)
			)
			(layer "F.SilkS")
		)
		(fp_line
			(start 1.538478 1.150874)
			(end 1.538478 -1.150874)
			(stroke
				(width 0.1524)
				(type default)
			)
			(layer "F.SilkS")
		)
		(fp_line
			(start -0.674878 -1.100074)
			(end -0.674878 1.100074)
			(stroke
				(width 0.1)
				(type default)
			)
			(layer "F.Fab")
		)
		(fp_line
			(start -0.674878 1.100074)
			(end 0.674878 1.100074)
			(stroke
				(width 0.1)
				(type default)
			)
			(layer "F.Fab")
		)
		(fp_line
			(start 0.674878 -1.100074)
			(end -0.674878 -1.100074)
			(stroke
				(width 0.1)
				(type default)
			)
			(layer "F.Fab")
		)
		(fp_line
			(start 0.674878 1.100074)
			(end 0.674878 -1.100074)
			(stroke
				(width 0.1)
				(type default)
			)
			(layer "F.Fab")
		)
		(pad "1" smd rect
			(at -0.94996 -0.649986 90)
			(size 0.7112 0.9144)
			(layers "F.Cu" "F.Mask" "F.Paste")
			(net "FAN_6_PWM_IL")
		)
		(pad "2" smd rect
			(at -0.94996 0.649986 90)
			(size 0.7112 0.9144)
			(layers "F.Cu" "F.Mask" "F.Paste")
			(net "FAN_6_PWM_OL")
		)
		(pad "3" smd rect
			(at 0.94996 0 90)
			(size 0.7112 0.9144)
			(layers "F.Cu" "F.Mask" "F.Paste")
			(net "FAN_6_PWM_BUF")
		)
	)
	(footprint ""
		(layer "F.Cu")
		(at 16.520922 -199.076056)
		(property "Reference" "C2045"
			(at 0 0 0)
			(layer "F.SilkS")
			(hide yes)
			(effects
				(font
					(size 1.27 1.27)
				)
			)
		)
		(property "Value" ""
			(at 0 0 0)
			(layer "F.Fab")
			(effects
				(font
					(size 1.27 1.27)
				)
			)
		)
		(duplicate_pad_numbers_are_jumpers no)
		(fp_line
			(start -0.7874 -0.4064)
			(end 0.7874 -0.4064)
			(stroke
				(width 0.1524)
				(type default)
			)
			(layer "F.SilkS")
		)
		(fp_line
			(start -0.7874 0.4064)
			(end -0.7874 -0.4064)
			(stroke
				(width 0.1524)
				(type default)
			)
			(layer "F.SilkS")
		)
		(fp_line
			(start 0.7874 -0.4064)
			(end 0.7874 0.4064)
			(stroke
				(width 0.1524)
				(type default)
			)
			(layer "F.SilkS")
		)
		(fp_line
			(start 0.7874 0.4064)
			(end -0.7874 0.4064)
			(stroke
				(width 0.1524)
				(type default)
			)
			(layer "F.SilkS")
		)
		(fp_line
			(start -0.67945 -0.305054)
			(end -0.12065 -0.305054)
			(stroke
				(width 0.1)
				(type default)
			)
			(layer "F.Fab")
		)
		(fp_line
			(start -0.67945 0.3048)
			(end -0.67945 -0.305054)
			(stroke
				(width 0.1)
				(type default)
			)
			(layer "F.Fab")
		)
		(fp_line
			(start -0.12065 -0.305054)
			(end -0.12065 -0.2794)
			(stroke
				(width 0.1)
				(type default)
			)
			(layer "F.Fab")
		)
		(fp_line
			(start -0.12065 -0.2794)
			(end 0.12065 -0.2794)
			(stroke
				(width 0.1)
				(type default)
			)
			(layer "F.Fab")
		)
		(fp_line
			(start -0.12065 0.2794)
			(end -0.12065 0.3048)
			(stroke
				(width 0.1)
				(type default)
			)
			(layer "F.Fab")
		)
		(fp_line
			(start -0.12065 0.3048)
			(end -0.67945 0.3048)
			(stroke
				(width 0.1)
				(type default)
			)
			(layer "F.Fab")
		)
		(fp_line
			(start 0.120396 0.2794)
			(end -0.12065 0.2794)
			(stroke
				(width 0.1)
				(type default)
			)
			(layer "F.Fab")
		)
		(fp_line
			(start 0.120396 0.3048)
			(end 0.120396 0.2794)
			(stroke
				(width 0.1)
				(type default)
			)
			(layer "F.Fab")
		)
		(fp_line
			(start 0.12065 -0.3048)
			(end 0.67945 -0.3048)
			(stroke
				(width 0.1)
				(type default)
			)
			(layer "F.Fab")
		)
		(fp_line
			(start 0.12065 -0.2794)
			(end 0.12065 -0.3048)
			(stroke
				(width 0.1)
				(type default)
			)
			(layer "F.Fab")
		)
		(fp_line
			(start 0.67945 -0.3048)
			(end 0.67945 0.3048)
			(stroke
				(width 0.1)
				(type default)
			)
			(layer "F.Fab")
		)
		(fp_line
			(start 0.67945 0.3048)
			(end 0.120396 0.3048)
			(stroke
				(width 0.1)
				(type default)
			)
			(layer "F.Fab")
		)
		(pad "1" smd circle
			(at -0.40005 0)
			(size 0 0)
			(layers "F.Cu" "F.Mask" "F.Paste")
			(net "FAN_6_PWM_IL_R")
		)
		(pad "2" smd circle
			(at 0.40005 0)
			(size 0 0)
			(layers "F.Cu" "F.Mask" "F.Paste")
			(net "GND")
		)
	)
	(footprint ""
		(layer "F.Cu")
		(at 33.528 -176.403)
		(property "Reference" "R5102"
			(at 0 0 0)
			(layer "F.SilkS")
			(hide yes)
			(effects
				(font
					(size 1.27 1.27)
				)
			)
		)
		(property "Value" ""
			(at 0 0 0)
			(layer "F.Fab")
			(effects
				(font
					(size 1.27 1.27)
				)
			)
		)
		(duplicate_pad_numbers_are_jumpers no)
		(fp_line
			(start -0.7874 -0.4064)
			(end 0.7874 -0.4064)
			(stroke
				(width 0.1524)
				(type default)
			)
			(layer "F.SilkS")
		)
		(fp_line
			(start -0.7874 0.4064)
			(end -0.7874 -0.4064)
			(stroke
				(width 0.1524)
				(type default)
			)
			(layer "F.SilkS")
		)
		(fp_line
			(start 0.7874 -0.4064)
			(end 0.7874 0.4064)
			(stroke
				(width 0.1524)
				(type default)
			)
			(layer "F.SilkS")
		)
		(fp_line
			(start 0.7874 0.4064)
			(end -0.7874 0.4064)
			(stroke
				(width 0.1524)
				(type default)
			)
			(layer "F.SilkS")
		)
		(fp_line
			(start -0.67945 -0.305054)
			(end -0.12065 -0.305054)
			(stroke
				(width 0.1)
				(type default)
			)
			(layer "F.Fab")
		)
		(fp_line
			(start -0.67945 0.3048)
			(end -0.67945 -0.305054)
			(stroke
				(width 0.1)
				(type default)
			)
			(layer "F.Fab")
		)
		(fp_line
			(start -0.12065 -0.305054)
			(end -0.12065 -0.2794)
			(stroke
				(width 0.1)
				(type default)
			)
			(layer "F.Fab")
		)
		(fp_line
			(start -0.12065 -0.2794)
			(end 0.12065 -0.2794)
			(stroke
				(width 0.1)
				(type default)
			)
			(layer "F.Fab")
		)
		(fp_line
			(start -0.12065 0.2794)
			(end -0.12065 0.3048)
			(stroke
				(width 0.1)
				(type default)
			)
			(layer "F.Fab")
		)
		(fp_line
			(start -0.12065 0.3048)
			(end -0.67945 0.3048)
			(stroke
				(width 0.1)
				(type default)
			)
			(layer "F.Fab")
		)
		(fp_line
			(start 0.120396 0.2794)
			(end -0.12065 0.2794)
			(stroke
				(width 0.1)
				(type default)
			)
			(layer "F.Fab")
		)
		(fp_line
			(start 0.120396 0.3048)
			(end 0.120396 0.2794)
			(stroke
				(width 0.1)
				(type default)
			)
			(layer "F.Fab")
		)
		(fp_line
			(start 0.12065 -0.3048)
			(end 0.67945 -0.3048)
			(stroke
				(width 0.1)
				(type default)
			)
			(layer "F.Fab")
		)
		(fp_line
			(start 0.12065 -0.2794)
			(end 0.12065 -0.3048)
			(stroke
				(width 0.1)
				(type default)
			)
			(layer "F.Fab")
		)
		(fp_line
			(start 0.67945 -0.3048)
			(end 0.67945 0.3048)
			(stroke
				(width 0.1)
				(type default)
			)
			(layer "F.Fab")
		)
		(fp_line
			(start 0.67945 0.3048)
			(end 0.120396 0.3048)
			(stroke
				(width 0.1)
				(type default)
			)
			(layer "F.Fab")
		)
		(pad "1" smd circle
			(at -0.40005 0)
			(size 0 0)
			(layers "F.Cu" "F.Mask" "F.Paste")
			(net "FAN_4_OK_LED")
		)
		(pad "2" smd circle
			(at 0.40005 0)
			(size 0 0)
			(layers "F.Cu" "F.Mask" "F.Paste")
			(net "FAN_4_OK_R_LED")
		)
	)
	(footprint ""
		(layer "F.Cu")
		(at 17.272 -298.704 180)
		(property "Reference" "U366"
			(at -0.508 -1.80467 0)
			(unlocked yes)
			(layer "F.SilkS")
			(effects
				(font
					(size 0.7874 0.5842)
					(thickness 0.1524)
				)
				(justify left)
			)
		)
		(property "Value" ""
			(at 0 0 180)
			(layer "F.Fab")
			(effects
				(font
					(size 1.27 1.27)
				)
			)
		)
		(duplicate_pad_numbers_are_jumpers no)
		(fp_line
			(start 1.335278 1.100074)
			(end 1.335278 -1.100074)
			(stroke
				(width 0.1524)
				(type default)
			)
			(layer "F.SilkS")
		)
		(fp_line
			(start 1.335278 -1.100074)
			(end -1.335278 -1.100074)
			(stroke
				(width 0.1524)
				(type default)
			)
			(layer "F.SilkS")
		)
		(fp_line
			(start -1.335278 1.100074)
			(end 1.335278 1.100074)
			(stroke
				(width 0.1524)
				(type default)
			)
			(layer "F.SilkS")
		)
		(fp_line
			(start -1.335278 -1.100074)
			(end -1.335278 1.100074)
			(stroke
				(width 0.1524)
				(type default)
			)
			(layer "F.SilkS")
		)
		(fp_line
			(start 0.674878 1.100074)
			(end 0.674878 -1.100074)
			(stroke
				(width 0.1)
				(type default)
			)
			(layer "F.Fab")
		)
		(fp_line
			(start 0.674878 -1.100074)
			(end -0.674878 -1.100074)
			(stroke
				(width 0.1)
				(type default)
			)
			(layer "F.Fab")
		)
		(fp_line
			(start -0.674878 1.100074)
			(end 0.674878 1.100074)
			(stroke
				(width 0.1)
				(type default)
			)
			(layer "F.Fab")
		)
		(fp_line
			(start -0.674878 -1.100074)
			(end -0.674878 1.100074)
			(stroke
				(width 0.1)
				(type default)
			)
			(layer "F.Fab")
		)
		(pad "D" smd rect
			(at 0.8001 0 90)
			(size 0.6096 0.8128)
			(layers "F.Cu" "F.Mask" "F.Paste")
			(net "FAN_7_OK_LED_R_N")
		)
		(pad "G" smd rect
			(at -0.8001 -0.649986 90)
			(size 0.6096 0.8128)
			(layers "F.Cu" "F.Mask" "F.Paste")
			(net "FAN_7_OK_R_LED")
		)
		(pad "S" smd rect
			(at -0.8001 0.649986 90)
			(size 0.6096 0.8128)
			(layers "F.Cu" "F.Mask" "F.Paste")
			(net "GND")
		)
	)
	(footprint ""
		(layer "F.Cu")
		(at 32.258 -198.755 90)
		(property "Reference" "R5391"
			(at 0 0 90)
			(layer "F.SilkS")
			(hide yes)
			(effects
				(font
					(size 1.27 1.27)
				)
			)
		)
		(property "Value" ""
			(at 0 0 90)
			(layer "F.Fab")
			(effects
				(font
					(size 1.27 1.27)
				)
			)
		)
		(duplicate_pad_numbers_are_jumpers no)
		(fp_line
			(start 0.7874 -0.4064)
			(end 0.7874 0.4064)
			(stroke
				(width 0.1524)
				(type default)
			)
			(layer "F.SilkS")
		)
		(fp_line
			(start -0.7874 -0.4064)
			(end 0.7874 -0.4064)
			(stroke
				(width 0.1524)
				(type default)
			)
			(layer "F.SilkS")
		)
		(fp_line
			(start 0.7874 0.4064)
			(end -0.7874 0.4064)
			(stroke
				(width 0.1524)
				(type default)
			)
			(layer "F.SilkS")
		)
		(fp_line
			(start -0.7874 0.4064)
			(end -0.7874 -0.4064)
			(stroke
				(width 0.1524)
				(type default)
			)
			(layer "F.SilkS")
		)
		(fp_line
			(start -0.12065 -0.305054)
			(end -0.12065 -0.2794)
			(stroke
				(width 0.1)
				(type default)
			)
			(layer "F.Fab")
		)
		(fp_line
			(start -0.67945 -0.305054)
			(end -0.12065 -0.305054)
			(stroke
				(width 0.1)
				(type default)
			)
			(layer "F.Fab")
		)
		(fp_line
			(start 0.67945 -0.3048)
			(end 0.67945 0.3048)
			(stroke
				(width 0.1)
				(type default)
			)
			(layer "F.Fab")
		)
		(fp_line
			(start 0.12065 -0.3048)
			(end 0.67945 -0.3048)
			(stroke
				(width 0.1)
				(type default)
			)
			(layer "F.Fab")
		)
		(fp_line
			(start 0.12065 -0.2794)
			(end 0.12065 -0.3048)
			(stroke
				(width 0.1)
				(type default)
			)
			(layer "F.Fab")
		)
		(fp_line
			(start -0.12065 -0.2794)
			(end 0.12065 -0.2794)
			(stroke
				(width 0.1)
				(type default)
			)
			(layer "F.Fab")
		)
		(fp_line
			(start 0.120396 0.2794)
			(end -0.12065 0.2794)
			(stroke
				(width 0.1)
				(type default)
			)
			(layer "F.Fab")
		)
		(fp_line
			(start -0.12065 0.2794)
			(end -0.12065 0.3048)
			(stroke
				(width 0.1)
				(type default)
			)
			(layer "F.Fab")
		)
		(fp_line
			(start 0.67945 0.3048)
			(end 0.120396 0.3048)
			(stroke
				(width 0.1)
				(type default)
			)
			(layer "F.Fab")
		)
		(fp_line
			(start 0.120396 0.3048)
			(end 0.120396 0.2794)
			(stroke
				(width 0.1)
				(type default)
			)
			(layer "F.Fab")
		)
		(fp_line
			(start -0.12065 0.3048)
			(end -0.67945 0.3048)
			(stroke
				(width 0.1)
				(type default)
			)
			(layer "F.Fab")
		)
		(fp_line
			(start -0.67945 0.3048)
			(end -0.67945 -0.305054)
			(stroke
				(width 0.1)
				(type default)
			)
			(layer "F.Fab")
		)
		(pad "1" smd circle
			(at -0.40005 0 90)
			(size 0 0)
			(layers "F.Cu" "F.Mask" "F.Paste")
			(net "P3V3_AUX")
		)
		(pad "2" smd circle
			(at 0.40005 0 90)
			(size 0 0)
			(layers "F.Cu" "F.Mask" "F.Paste")
			(net "FAN_1_OK_R_LED")
		)
	)
	(footprint ""
		(layer "F.Cu")
		(at 37.084 -249.047)
		(property "Reference" "PR31"
			(at 0 0 0)
			(layer "F.SilkS")
			(hide yes)
			(effects
				(font
					(size 1.27 1.27)
				)
			)
		)
		(property "Value" ""
			(at 0 0 0)
			(layer "F.Fab")
			(effects
				(font
					(size 1.27 1.27)
				)
			)
		)
		(duplicate_pad_numbers_are_jumpers no)
		(fp_line
			(start -0.7874 -0.4064)
			(end 0.7874 -0.4064)
			(stroke
				(width 0.1524)
				(type default)
			)
			(layer "F.SilkS")
		)
		(fp_line
			(start -0.7874 0.4064)
			(end -0.7874 -0.4064)
			(stroke
				(width 0.1524)
				(type default)
			)
			(layer "F.SilkS")
		)
		(fp_line
			(start 0.7874 -0.4064)
			(end 0.7874 0.4064)
			(stroke
				(width 0.1524)
				(type default)
			)
			(layer "F.SilkS")
		)
		(fp_line
			(start 0.7874 0.4064)
			(end -0.7874 0.4064)
			(stroke
				(width 0.1524)
				(type default)
			)
			(layer "F.SilkS")
		)
		(fp_line
			(start -0.67945 -0.305054)
			(end -0.12065 -0.305054)
			(stroke
				(width 0.1)
				(type default)
			)
			(layer "F.Fab")
		)
		(fp_line
			(start -0.67945 0.3048)
			(end -0.67945 -0.305054)
			(stroke
				(width 0.1)
				(type default)
			)
			(layer "F.Fab")
		)
		(fp_line
			(start -0.12065 -0.305054)
			(end -0.12065 -0.2794)
			(stroke
				(width 0.1)
				(type default)
			)
			(layer "F.Fab")
		)
		(fp_line
			(start -0.12065 -0.2794)
			(end 0.12065 -0.2794)
			(stroke
				(width 0.1)
				(type default)
			)
			(layer "F.Fab")
		)
		(fp_line
			(start -0.12065 0.2794)
			(end -0.12065 0.3048)
			(stroke
				(width 0.1)
				(type default)
			)
			(layer "F.Fab")
		)
		(fp_line
			(start -0.12065 0.3048)
			(end -0.67945 0.3048)
			(stroke
				(width 0.1)
				(type default)
			)
			(layer "F.Fab")
		)
		(fp_line
			(start 0.120396 0.2794)
			(end -0.12065 0.2794)
			(stroke
				(width 0.1)
				(type default)
			)
			(layer "F.Fab")
		)
		(fp_line
			(start 0.120396 0.3048)
			(end 0.120396 0.2794)
			(stroke
				(width 0.1)
				(type default)
			)
			(layer "F.Fab")
		)
		(fp_line
			(start 0.12065 -0.3048)
			(end 0.67945 -0.3048)
			(stroke
				(width 0.1)
				(type default)
			)
			(layer "F.Fab")
		)
		(fp_line
			(start 0.12065 -0.2794)
			(end 0.12065 -0.3048)
			(stroke
				(width 0.1)
				(type default)
			)
			(layer "F.Fab")
		)
		(fp_line
			(start 0.67945 -0.3048)
			(end 0.67945 0.3048)
			(stroke
				(width 0.1)
				(type default)
			)
			(layer "F.Fab")
		)
		(fp_line
			(start 0.67945 0.3048)
			(end 0.120396 0.3048)
			(stroke
				(width 0.1)
				(type default)
			)
			(layer "F.Fab")
		)
		(pad "1" smd circle
			(at -0.40005 0)
			(size 0 0)
			(layers "F.Cu" "F.Mask" "F.Paste")
			(net "FAN_1_MODE")
		)
		(pad "2" smd circle
			(at 0.40005 0)
			(size 0 0)
			(layers "F.Cu" "F.Mask" "F.Paste")
			(net "GND")
		)
	)
)
